# T6G (Grand Teton) — schematic netlist excerpt (pin names and nets, part order shuffled) for the footprints in the layout excerpt that follows; sources: Cadence DE-HDL packaged netlist, KiCad conversion of 04192023_DAF0TMB3IC0_F0TG_MB_C_brd_V02_OCP.brd

C445  Q_CAP  0.1UF 10V 10% X7S  pkg C0201  page 356 : A = P1V8_CPU1_RT3_1A ; B = GND

J118  PICOPROBE_BXA  DELTA-L 4.0 EMPTY  pkg TRIANG_LAUNCH_3PXB  page 229
  \1_p\  = DELTA_L_85_10INCH_IN5_DP
  \2_n\  = DELTA_L_85_10INCH_IN5_DN
  \3_g\  = DELTA_L_GND_1

(kicad_pcb
	(version 20260206)
	(generator "pcbnew")
	(generator_version "10.0")
	(general
		(thickness 1.6)
		(legacy_teardrops no)
	)
	(paper "A4")
	(title_block
		(title "04192023_DAF0TMB3IC0_F0TG_MB_C_brd_V02_OCP.brd")
		(comment 1 "Grand Teton / footprints 7491-7492 of 8354")
	)
	(layers
		(0 "F.Cu" signal "TOP")
		(4 "In1.Cu" signal "GND")
		(6 "In2.Cu" signal "IN1")
		(8 "In3.Cu" signal "GND1")
		(10 "In4.Cu" signal "IN2")
		(12 "In5.Cu" signal "GND2")
		(14 "In6.Cu" signal "IN3")
		(16 "In7.Cu" signal "GND3")
		(18 "In8.Cu" signal "VCC")
		(20 "In9.Cu" signal "VCC1")
		(22 "In10.Cu" signal "GND4")
		(24 "In11.Cu" signal "IN4")
		(26 "In12.Cu" signal "GND5")
		(28 "In13.Cu" signal "IN5")
		(30 "In14.Cu" signal "GND6")
		(32 "In15.Cu" signal "IN6")
		(34 "In16.Cu" signal "GND7")
		(2 "B.Cu" signal "BOTTOM")
		(9 "F.Adhes" user "F.Adhesive")
		(11 "B.Adhes" user "B.Adhesive")
		(13 "F.Paste" user "Package Geometry/Pastemask Top")
		(15 "B.Paste" user "Package Geometry/Pastemask Bottom")
		(5 "F.SilkS" user "Ref Des/Silkscreen Top")
		(7 "B.SilkS" user "Ref Des/Silkscreen Bottom")
		(1 "F.Mask" user "Board Geometry/Soldermask Top")
		(3 "B.Mask" user "Board Geometry/Soldermask Bottom")
		(17 "Dwgs.User" user "User.Drawings")
		(19 "Cmts.User" user "User.Comments")
		(21 "Eco1.User" user "User.Eco1")
		(23 "Eco2.User" user "User.Eco2")
		(25 "Edge.Cuts" user "Board Geometry/Outline")
		(27 "Margin" user)
		(31 "F.CrtYd" user "Package Geometry/Place Bound Top")
		(29 "B.CrtYd" user "Package Geometry/Place Bound Bottom")
		(35 "F.Fab" user "Ref Des/Assembly Top")
		(33 "B.Fab" user "Ref Des/Assembly Bottom")
	)
	(footprint ""
		(layer "B.Cu")
		(at 97.795842 3.523234 180)
		(property "Reference" "J118"
			(at 4.737608 -1.817624 270)
			(unlocked yes)
			(layer "B.SilkS")
			(effects
				(font
					(size 0.7874 0.5842)
					(thickness 0.1524)
				)
				(justify left mirror)
			)
		)
		(property "Value" ""
			(at 0 0 0)
			(layer "B.Fab")
			(effects
				(font
					(size 1.27 1.27)
				)
				(justify mirror)
			)
		)
		(duplicate_pad_numbers_are_jumpers no)
		(fp_line
			(start 1.2192 2.06756)
			(end 1.2192 -2.06756)
			(stroke
				(width 0.1524)
				(type default)
			)
			(layer "B.SilkS")
		)
		(fp_line
			(start 1.2192 -2.06756)
			(end -1.2192 -2.06756)
			(stroke
				(width 0.1524)
				(type default)
			)
			(layer "B.SilkS")
		)
		(fp_line
			(start -1.2192 2.06756)
			(end 1.2192 2.06756)
			(stroke
				(width 0.1524)
				(type default)
			)
			(layer "B.SilkS")
		)
		(fp_line
			(start -1.2192 -2.06756)
			(end -1.2192 2.06756)
			(stroke
				(width 0.1524)
				(type default)
			)
			(layer "B.SilkS")
		)
		(pad "" np_thru_hole circle
			(at -3.4671 -1.27 90)
			(size 1.0414 1.0414)
			(drill 1.0414)
			(layers "*.Cu" "*.Mask")
			(clearance 0.381)
			(thermal_gap 0.381)
		)
		(pad "" np_thru_hole circle
			(at -3.4671 1.27 90)
			(size 1.0414 1.0414)
			(drill 1.0414)
			(layers "*.Cu" "*.Mask")
			(clearance 0.381)
			(thermal_gap 0.381)
		)
		(pad "" np_thru_hole circle
			(at 2.8829 -1.27 90)
			(size 1.0414 1.0414)
			(drill 1.0414)
			(layers "*.Cu" "*.Mask")
			(clearance 0.381)
			(thermal_gap 0.381)
		)
		(pad "" np_thru_hole circle
			(at 2.8829 1.27 90)
			(size 1.0414 1.0414)
			(drill 1.0414)
			(layers "*.Cu" "*.Mask")
			(clearance 0.381)
			(thermal_gap 0.381)
		)
		(pad "1" smd rect
			(at -0.8255 -0.249936 90)
			(size 0.3048 0.508)
			(layers "B.Cu" "B.Mask" "B.Paste")
			(net "DELTA_L_85_10INCH_IN5_DP")
		)
		(pad "2" smd rect
			(at -0.8255 0.249936 90)
			(size 0.3048 0.508)
			(layers "B.Cu" "B.Mask" "B.Paste")
			(net "DELTA_L_85_10INCH_IN5_DN")
		)
		(pad "3" smd circle
			(at 0 0)
			(size 0 0)
			(layers "B.Cu" "B.Mask" "B.Paste")
			(net "DELTA_L_GND_1")
		)
		(zone
			(layers "F.Cu" "B.Cu" "In1.Cu" "In2.Cu" "In3.Cu" "In4.Cu" "In5.Cu" "In6.Cu"
				"In7.Cu" "In8.Cu" "In9.Cu" "In10.Cu" "In11.Cu" "In12.Cu" "In13.Cu" "In14.Cu"
				"In15.Cu" "In16.Cu"
			)
			(hatch none 0.5)
			(connect_pads
				(clearance 0)
			)
			(min_thickness 0.25)
			(keepout
				(tracks not_allowed)
				(vias allowed)
				(pads allowed)
				(copperpour not_allowed)
				(footprints allowed)
			)
			(placement
				(enabled no)
				(sheetname "")
			)
			(fill
				(thermal_gap 0.5)
				(thermal_bridge_width 0.5)
				(island_removal_mode 0)
			)
			(polygon
				(pts
					(arc
						(start 95.840042 2.253234)
						(mid 93.985842 2.253234)
						(end 95.840042 2.253234)
					)
				)
			)
		)
		(zone
			(layers "F.Cu" "B.Cu" "In1.Cu" "In2.Cu" "In3.Cu" "In4.Cu" "In5.Cu" "In6.Cu"
				"In7.Cu" "In8.Cu" "In9.Cu" "In10.Cu" "In11.Cu" "In12.Cu" "In13.Cu" "In14.Cu"
				"In15.Cu" "In16.Cu"
			)
			(hatch none 0.5)
			(connect_pads
				(clearance 0)
			)
			(min_thickness 0.25)
			(keepout
				(tracks not_allowed)
				(vias allowed)
				(pads allowed)
				(copperpour not_allowed)
				(footprints allowed)
			)
			(placement
				(enabled no)
				(sheetname "")
			)
			(fill
				(thermal_gap 0.5)
				(thermal_bridge_width 0.5)
				(island_removal_mode 0)
			)
			(polygon
				(pts
					(arc
						(start 95.840042 4.793234)
						(mid 93.985842 4.793234)
						(end 95.840042 4.793234)
					)
				)
			)
		)
		(zone
			(layers "F.Cu" "B.Cu" "In1.Cu" "In2.Cu" "In3.Cu" "In4.Cu" "In5.Cu" "In6.Cu"
				"In7.Cu" "In8.Cu" "In9.Cu" "In10.Cu" "In11.Cu" "In12.Cu" "In13.Cu" "In14.Cu"
				"In15.Cu" "In16.Cu"
			)
			(hatch none 0.5)
			(connect_pads
				(clearance 0)
			)
			(min_thickness 0.25)
			(keepout
				(tracks not_allowed)
				(vias allowed)
				(pads allowed)
				(copperpour not_allowed)
				(footprints allowed)
			)
			(placement
				(enabled no)
				(sheetname "")
			)
			(fill
				(thermal_gap 0.5)
				(thermal_bridge_width 0.5)
				(island_removal_mode 0)
			)
			(polygon
				(pts
					(arc
						(start 102.190042 2.253234)
						(mid 100.335842 2.253234)
						(end 102.190042 2.253234)
					)
				)
			)
		)
		(zone
			(layers "F.Cu" "B.Cu" "In1.Cu" "In2.Cu" "In3.Cu" "In4.Cu" "In5.Cu" "In6.Cu"
				"In7.Cu" "In8.Cu" "In9.Cu" "In10.Cu" "In11.Cu" "In12.Cu" "In13.Cu" "In14.Cu"
				"In15.Cu" "In16.Cu"
			)
			(hatch none 0.5)
			(connect_pads
				(clearance 0)
			)
			(min_thickness 0.25)
			(keepout
				(tracks not_allowed)
				(vias allowed)
				(pads allowed)
				(copperpour not_allowed)
				(footprints allowed)
			)
			(placement
				(enabled no)
				(sheetname "")
			)
			(fill
				(thermal_gap 0.5)
				(thermal_bridge_width 0.5)
				(island_removal_mode 0)
			)
			(polygon
				(pts
					(arc
						(start 102.190042 4.793234)
						(mid 100.335842 4.793234)
						(end 102.190042 4.793234)
					)
				)
			)
		)
		(zone
			(layer "B.Cu")
			(hatch none 0.5)
			(connect_pads
				(clearance 0)
			)
			(min_thickness 0.25)
			(keepout
				(tracks not_allowed)
				(vias allowed)
				(pads allowed)
				(copperpour not_allowed)
				(footprints allowed)
			)
			(placement
				(enabled no)
				(sheetname "")
			)
			(fill
				(thermal_gap 0.5)
				(thermal_bridge_width 0.5)
				(island_removal_mode 0)
			)
			(polygon
				(pts
					(xy 98.913442 4.071874) (xy 98.913442 3.97637) (xy 98.316542 3.97637) (xy 98.316542 3.56997) (xy 98.913442 3.56997)
					(xy 98.913442 3.476498) (xy 98.316542 3.476498) (xy 98.316542 3.070098) (xy 98.913442 3.070098)
					(xy 98.913442 2.974594) (xy 98.214942 2.974594) (xy 98.214942 4.071874)
				)
			)
		)
	)
	(footprint ""
		(layer "B.Cu")
		(at 124.078492 -386.766562 90)
		(property "Reference" "C445"
			(at 0 0 90)
			(layer "B.SilkS")
			(hide yes)
			(effects
				(font
					(size 1.27 1.27)
				)
				(justify mirror)
			)
		)
		(property "Value" ""
			(at 0 0 90)
			(layer "B.Fab")
			(effects
				(font
					(size 1.27 1.27)
				)
				(justify mirror)
			)
		)
		(duplicate_pad_numbers_are_jumpers no)
		(fp_line
			(start 0.299974 -0.150114)
			(end -0.299974 -0.150114)
			(stroke
				(width 0.1)
				(type default)
			)
			(layer "B.Fab")
		)
		(fp_line
			(start -0.299974 -0.150114)
			(end -0.299974 0.150114)
			(stroke
				(width 0.1)
				(type default)
			)
			(layer "B.Fab")
		)
		(fp_line
			(start 0.299974 0.150114)
			(end 0.299974 -0.150114)
			(stroke
				(width 0.1)
				(type default)
			)
			(layer "B.Fab")
		)
		(fp_line
			(start -0.299974 0.150114)
			(end 0.299974 0.150114)
			(stroke
				(width 0.1)
				(type default)
			)
			(layer "B.Fab")
		)
		(pad "1" smd rect
			(at 0.2667 0 270)
			(size 0.3048 0.381)
			(layers "B.Cu" "B.Mask" "B.Paste")
			(net "P1V8_CPU1_RT3_1A")
		)
		(pad "2" smd rect
			(at -0.2667 0 270)
			(size 0.3048 0.381)
			(layers "B.Cu" "B.Mask" "B.Paste")
			(net "GND")
		)
	)
)
